(kicad_pcb
	(version 20241229)
	(generator "pcbnew")
	(generator_version "9.0")
	(general
		(thickness 0.876)
		(legacy_teardrops no)
	)
	(paper "A4")
	(title_block
		(rev "1.2.2")
		(comment 9 "footprints 1-3 of 20")
	)
	(layers
		(0 "F.Cu" signal)
		(4 "In1.Cu" signal)
		(6 "In2.Cu" signal)
		(2 "B.Cu" signal)
		(9 "F.Adhes" user "F.Adhesive")
		(11 "B.Adhes" user "B.Adhesive")
		(13 "F.Paste" user)
		(15 "B.Paste" user)
		(5 "F.SilkS" user "F.Silkscreen")
		(7 "B.SilkS" user "B.Silkscreen")
		(1 "F.Mask" user)
		(3 "B.Mask" user)
		(17 "Dwgs.User" user "User.Drawings")
		(19 "Cmts.User" user "User.Comments")
		(21 "Eco1.User" user "User.Eco1")
		(23 "Eco2.User" user "User.Eco2")
		(25 "Edge.Cuts" user)
		(27 "Margin" user)
		(31 "F.CrtYd" user "F.Courtyard")
		(29 "B.CrtYd" user "B.Courtyard")
		(35 "F.Fab" user)
		(33 "B.Fab" user)
	)
	(footprint "antmicro-footprints:Socket_Samtec_PCIE_PCIe-x4_PCIE-064-02-X-D-EMSX"
		(layer "F.Cu")
		(at 131.660059 124.712277 180)
		(property "Reference" "J1"
			(at -16.84 9.265 180)
			(layer "F.SilkS")
			(effects
				(font
					(size 0.7 0.7)
					(thickness 0.15)
				)
				(justify left bottom)
			)
		)
		(property "Value" "Socket_Samtec_PCIE_PCIe-x4_PCIE-064-02-X-D-EMSX"
			(at 0 11.3 180)
			(layer "F.Fab")
			(effects
				(font
					(size 0.7 0.7)
					(thickness 0.15)
				)
				(justify left bottom)
			)
		)
		(property "Datasheet" "http://www.farnell.com/datasheets/2048385.pdf?_ga=2.224413790.550525831.1572511829-156563690.1566371002&_gac=1.194368863.1572511829.Cj0KCQjwjOrtBRCcARIsAEq4rW4MDAz553xUSGW1I2S05saoepO8CZq5otyVO6_gct6IiE-jnZiday4aAmKSEALw_wcB"
			(at 0 0 180)
			(layer "F.Fab")
			(hide yes)
			(effects
				(font
					(size 1.27 1.27)
					(thickness 0.15)
				)
			)
		)
		(property "Description" "PCIe x4 connector"
			(at 0 0 180)
			(layer "F.Fab")
			(hide yes)
			(effects
				(font
					(size 1.27 1.27)
					(thickness 0.15)
				)
			)
		)
		(property "Author" "Antmicro"
			(at 263.320118 249.424554 0)
			(layer "F.Fab")
			(hide yes)
			(effects
				(font
					(size 1 1)
					(thickness 0.15)
				)
			)
		)
		(property "License" "Apache-2.0"
			(at 263.320118 249.424554 0)
			(layer "F.Fab")
			(hide yes)
			(effects
				(font
					(size 1 1)
					(thickness 0.15)
				)
			)
		)
		(property "MPN" "PCIE-064-02-X-D-EMSX"
			(at 263.320118 249.424554 0)
			(layer "F.Fab")
			(hide yes)
			(effects
				(font
					(size 1 1)
					(thickness 0.15)
				)
			)
		)
		(property "Manufacturer" "Samtec"
			(at 263.320118 249.424554 0)
			(layer "F.Fab")
			(hide yes)
			(effects
				(font
					(size 1 1)
					(thickness 0.15)
				)
			)
		)
		(sheetname "/")
		(sheetfile "m2-pcie-adapter.kicad_sch")
		(attr smd)
		(fp_circle
			(center -17.1 7.6)
			(end -17.05 7.6)
			(stroke
				(width 0.15)
				(type solid)
			)
			(fill yes)
			(layer "F.SilkS")
		)
		(fp_rect
			(start -20.5 -9.03)
			(end 20.5 9.03)
			(stroke
				(width 0.05)
				(type solid)
			)
			(fill no)
			(layer "F.CrtYd")
		)
		(pad "A1" smd rect
			(at -16.55 5.9 180)
			(size 0.7 4.2)
			(layers "B.Cu" "B.Mask" "B.Paste")
			(net 16 "unconnected-(J1-PRSNT#1-PadA1)")
			(pinfunction "PRSNT#1")
			(pintype "passive+no_connect")
		)
		(pad "A2" smd rect
			(at -15.55 5.9 180)
			(size 0.7 4.2)
			(layers "B.Cu" "B.Mask" "B.Paste")
			(net 30 "+12V")
			(pinfunction "+12V")
			(pintype "passive")
		)
		(pad "A3" smd rect
			(at -14.55 5.9 180)
			(size 0.7 4.2)
			(layers "B.Cu" "B.Mask" "B.Paste")
			(net 30 "+12V")
			(pinfunction "+12V")
			(pintype "passive")
		)
		(pad "A4" smd rect
			(at -13.55 5.9 180)
			(size 0.7 4.2)
			(layers "B.Cu" "B.Mask" "B.Paste")
			(net 60 "GND")
			(pinfunction "GND")
			(pintype "passive")
		)
		(pad "A5" smd rect
			(at -12.55 5.9 180)
			(size 0.7 4.2)
			(layers "B.Cu" "B.Mask" "B.Paste")
			(net 15 "unconnected-(J1-JTAG2-PadA5)")
			(pinfunction "JTAG2")
			(pintype "passive+no_connect")
		)
		(pad "A6" smd rect
			(at -11.55 5.9 180)
			(size 0.7 4.2)
			(layers "B.Cu" "B.Mask" "B.Paste")
			(net 14 "unconnected-(J1-JTAG3-PadA6)")
			(pinfunction "JTAG3")
			(pintype "passive+no_connect")
		)
		(pad "A7" smd rect
			(at -10.55 5.9 180)
			(size 0.7 4.2)
			(layers "B.Cu" "B.Mask" "B.Paste")
			(net 13 "unconnected-(J1-JTAG4-PadA7)")
			(pinfunction "JTAG4")
			(pintype "passive+no_connect")
		)
		(pad "A8" smd rect
			(at -9.55 5.9 180)
			(size 0.7 4.2)
			(layers "B.Cu" "B.Mask" "B.Paste")
			(net 12 "unconnected-(J1-JTAG5-PadA8)")
			(pinfunction "JTAG5")
			(pintype "passive+no_connect")
		)
		(pad "A9" smd rect
			(at -8.55 5.9 180)
			(size 0.7 4.2)
			(layers "B.Cu" "B.Mask" "B.Paste")
			(net 31 "/+3V3")
			(pinfunction "+3V3")
			(pintype "passive")
		)
		(pad "A10" smd rect
			(at -7.55 5.9 180)
			(size 0.7 4.2)
			(layers "B.Cu" "B.Mask" "B.Paste")
			(net 31 "/+3V3")
			(pinfunction "+3V3")
			(pintype "passive")
		)
		(pad "A11" smd rect
			(at -6.55 5.9 180)
			(size 0.7 4.2)
			(layers "B.Cu" "B.Mask" "B.Paste")
			(net 11 "Net-(J1-PWRGD)")
			(pinfunction "PWRGD")
			(pintype "passive")
		)
		(pad "A12" smd rect
			(at -3.55 5.9 180)
			(size 0.7 4.2)
			(layers "B.Cu" "B.Mask" "B.Paste")
			(net 60 "GND")
			(pinfunction "GND")
			(pintype "passive")
		)
		(pad "A13" smd rect
			(at -2.55 5.9 180)
			(size 0.7 4.2)
			(layers "B.Cu" "B.Mask" "B.Paste")
			(net 32 "/REFCLK+")
			(pinfunction "REFCLK+")
			(pintype "passive")
		)
		(pad "A14" smd rect
			(at -1.55 5.9 180)
			(size 0.7 4.2)
			(layers "B.Cu" "B.Mask" "B.Paste")
			(net 33 "/REFCLK-")
			(pinfunction "REFCLK-")
			(pintype "passive")
		)
		(pad "A15" smd rect
			(at -0.55 5.9 180)
			(size 0.7 4.2)
			(layers "B.Cu" "B.Mask" "B.Paste")
			(net 60 "GND")
			(pinfunction "GND")
			(pintype "passive")
		)
		(pad "A16" smd rect
			(at 0.45 5.9 180)
			(size 0.7 4.2)
			(layers "B.Cu" "B.Mask" "B.Paste")
			(net 35 "/Data_0_IN_P")
			(pinfunction "HSIp(0)")
			(pintype "passive")
		)
		(pad "A17" smd rect
			(at 1.45 5.9 180)
			(size 0.7 4.2)
			(layers "B.Cu" "B.Mask" "B.Paste")
			(net 34 "/Data_0_IN_N")
			(pinfunction "HSIn(0)")
			(pintype "passive")
		)
		(pad "A18" smd rect
			(at 2.45 5.9 180)
			(size 0.7 4.2)
			(layers "B.Cu" "B.Mask" "B.Paste")
			(net 60 "GND")
			(pinfunction "GND")
			(pintype "passive")
		)
		(pad "A19" smd rect
			(at 3.45 5.9 180)
			(size 0.7 4.2)
			(layers "B.Cu" "B.Mask" "B.Paste")
			(net 10 "unconnected-(J1-RSVD-PadA19)")
			(pinfunction "RSVD")
			(pintype "passive+no_connect")
		)
		(pad "A20" smd rect
			(at 4.45 5.9 180)
			(size 0.7 4.2)
			(layers "B.Cu" "B.Mask" "B.Paste")
			(net 60 "GND")
			(pinfunction "GND")
			(pintype "passive")
		)
		(pad "A21" smd rect
			(at 5.45 5.9 180)
			(size 0.7 4.2)
			(layers "B.Cu" "B.Mask" "B.Paste")
			(net 39 "/Data_1_IN_P")
			(pinfunction "HSIp(1)")
			(pintype "passive")
		)
		(pad "A22" smd rect
			(at 6.45 5.9 180)
			(size 0.7 4.2)
			(layers "B.Cu" "B.Mask" "B.Paste")
			(net 38 "/Data_1_IN_N")
			(pinfunction "HSIn(1)")
			(pintype "passive")
		)
		(pad "A23" smd rect
			(at 7.45 5.9 180)
			(size 0.7 4.2)
			(layers "B.Cu" "B.Mask" "B.Paste")
			(net 60 "GND")
			(pinfunction "GND")
			(pintype "passive")
		)
		(pad "A24" smd rect
			(at 8.45 5.9 180)
			(size 0.7 4.2)
			(layers "B.Cu" "B.Mask" "B.Paste")
			(net 60 "GND")
			(pinfunction "GND")
			(pintype "passive")
		)
		(pad "A25" smd rect
			(at 9.45 5.9 180)
			(size 0.7 4.2)
			(layers "B.Cu" "B.Mask" "B.Paste")
			(net 43 "/Data_2_IN_P")
			(pinfunction "HSIp(2)")
			(pintype "passive")
		)
		(pad "A26" smd rect
			(at 10.45 5.9 180)
			(size 0.7 4.2)
			(layers "B.Cu" "B.Mask" "B.Paste")
			(net 42 "/Data_2_IN_N")
			(pinfunction "HSIn(2)")
			(pintype "passive")
		)
		(pad "A27" smd rect
			(at 11.45 5.9 180)
			(size 0.7 4.2)
			(layers "B.Cu" "B.Mask" "B.Paste")
			(net 60 "GND")
			(pinfunction "GND")
			(pintype "passive")
		)
		(pad "A28" smd rect
			(at 12.45 5.9 180)
			(size 0.7 4.2)
			(layers "B.Cu" "B.Mask" "B.Paste")
			(net 60 "GND")
			(pinfunction "GND")
			(pintype "input")
		)
		(pad "A29" smd rect
			(at 13.45 5.9 180)
			(size 0.7 4.2)
			(layers "B.Cu" "B.Mask" "B.Paste")
			(net 47 "/Data_3_IN_P")
			(pinfunction "HSIp(3)")
			(pintype "passive")
		)
		(pad "A30" smd rect
			(at 14.45 5.9 180)
			(size 0.7 4.2)
			(layers "B.Cu" "B.Mask" "B.Paste")
			(net 46 "/Data_3_IN_N")
			(pinfunction "HSIn(3)")
			(pintype "passive")
		)
		(pad "A31" smd rect
			(at 15.45 5.9 180)
			(size 0.7 4.2)
			(layers "B.Cu" "B.Mask" "B.Paste")
			(net 60 "GND")
			(pinfunction "GND")
			(pintype "passive")
		)
		(pad "A32" smd rect
			(at 16.45 5.9 180)
			(size 0.7 4.2)
			(layers "B.Cu" "B.Mask" "B.Paste")
			(net 9 "unconnected-(J1-RSVD-PadA32)")
			(pinfunction "RSVD")
			(pintype "passive+no_connect")
		)
		(pad "B1" smd rect
			(at -16.55 5.895 180)
			(size 0.7 4.2)
			(layers "F.Cu" "F.Mask" "F.Paste")
			(net 30 "+12V")
			(pinfunction "+12V")
			(pintype "passive")
		)
		(pad "B2" smd rect
			(at -15.55 5.895 180)
			(size 0.7 4.2)
			(layers "F.Cu" "F.Mask" "F.Paste")
			(net 30 "+12V")
			(pinfunction "+12V")
			(pintype "passive")
		)
		(pad "B3" smd rect
			(at -14.55 5.895 180)
			(size 0.7 4.2)
			(layers "F.Cu" "F.Mask" "F.Paste")
			(net 30 "+12V")
			(pinfunction "+12V")
			(pintype "passive")
		)
		(pad "B4" smd rect
			(at -13.55 5.895 180)
			(size 0.7 4.2)
			(layers "F.Cu" "F.Mask" "F.Paste")
			(net 60 "GND")
			(pinfunction "GND")
			(pintype "passive")
		)
		(pad "B5" smd rect
			(at -12.55 5.895 180)
			(size 0.7 4.2)
			(layers "F.Cu" "F.Mask" "F.Paste")
			(net 8 "unconnected-(J1-SMCLK-PadB5)")
			(pinfunction "SMCLK")
			(pintype "passive+no_connect")
		)
		(pad "B6" smd rect
			(at -11.55 5.895 180)
			(size 0.7 4.2)
			(layers "F.Cu" "F.Mask" "F.Paste")
			(net 7 "unconnected-(J1-SMDAT-PadB6)")
			(pinfunction "SMDAT")
			(pintype "passive+no_connect")
		)
		(pad "B7" smd rect
			(at -10.55 5.895 180)
			(size 0.7 4.2)
			(layers "F.Cu" "F.Mask" "F.Paste")
			(net 60 "GND")
			(pinfunction "GND")
			(pintype "passive")
		)
		(pad "B8" smd rect
			(at -9.55 5.895 180)
			(size 0.7 4.2)
			(layers "F.Cu" "F.Mask" "F.Paste")
			(net 31 "/+3V3")
			(pinfunction "+3V3")
			(pintype "passive")
		)
		(pad "B9" smd rect
			(at -8.55 5.895 180)
			(size 0.7 4.2)
			(layers "F.Cu" "F.Mask" "F.Paste")
			(net 6 "unconnected-(J1-JTAG1-PadB9)")
			(pinfunction "JTAG1")
			(pintype "passive+no_connect")
		)
		(pad "B10" smd rect
			(at -7.55 5.895 180)
			(size 0.7 4.2)
			(layers "F.Cu" "F.Mask" "F.Paste")
			(net 62 "/+3V3_AUX")
			(pinfunction "+3V3aux")
			(pintype "passive")
		)
		(pad "B11" smd rect
			(at -6.55 5.895 180)
			(size 0.7 4.2)
			(layers "F.Cu" "F.Mask" "F.Paste")
			(net 5 "Net-(J1-WAKE#)")
			(pinfunction "WAKE#")
			(pintype "passive")
		)
		(pad "B12" smd rect
			(at -3.55 5.895 180)
			(size 0.7 4.2)
			(layers "F.Cu" "F.Mask" "F.Paste")
			(net 4 "unconnected-(J1-RSVD-PadB12)")
			(pinfunction "RSVD")
			(pintype "passive+no_connect")
		)
		(pad "B13" smd rect
			(at -2.55 5.895 180)
			(size 0.7 4.2)
			(layers "F.Cu" "F.Mask" "F.Paste")
			(net 60 "GND")
			(pinfunction "GND")
			(pintype "passive")
		)
		(pad "B14" smd rect
			(at -1.55 5.895 180)
			(size 0.7 4.2)
			(layers "F.Cu" "F.Mask" "F.Paste")
			(net 36 "/Data_0_OUT_P")
			(pinfunction "HSOp(0)")
			(pintype "passive")
		)
		(pad "B15" smd rect
			(at -0.55 5.895 180)
			(size 0.7 4.2)
			(layers "F.Cu" "F.Mask" "F.Paste")
			(net 37 "/Data_0_OUT_N")
			(pinfunction "HSOn(0)")
			(pintype "passive")
		)
		(pad "B16" smd rect
			(at 0.45 5.895 180)
			(size 0.7 4.2)
			(layers "F.Cu" "F.Mask" "F.Paste")
			(net 60 "GND")
			(pinfunction "GND")
			(pintype "passive")
		)
		(pad "B17" smd rect
			(at 1.45 5.895 180)
			(size 0.7 4.2)
			(layers "F.Cu" "F.Mask" "F.Paste")
			(net 3 "unconnected-(J1-PRSNT#2-PadB17)")
			(pinfunction "PRSNT#2")
			(pintype "passive+no_connect")
		)
		(pad "B18" smd rect
			(at 2.45 5.895 180)
			(size 0.7 4.2)
			(layers "F.Cu" "F.Mask" "F.Paste")
			(net 60 "GND")
			(pinfunction "GND")
			(pintype "passive")
		)
		(pad "B19" smd rect
			(at 3.45 5.895 180)
			(size 0.7 4.2)
			(layers "F.Cu" "F.Mask" "F.Paste")
			(net 40 "/Data_1_OUT_P")
			(pinfunction "HSOp(1)")
			(pintype "passive")
		)
		(pad "B20" smd rect
			(at 4.45 5.895 180)
			(size 0.7 4.2)
			(layers "F.Cu" "F.Mask" "F.Paste")
			(net 41 "/Data_1_OUT_N")
			(pinfunction "HSOn(1)")
			(pintype "passive")
		)
		(pad "B21" smd rect
			(at 5.45 5.895 180)
			(size 0.7 4.2)
			(layers "F.Cu" "F.Mask" "F.Paste")
			(net 60 "GND")
			(pinfunction "GND")
			(pintype "passive")
		)
		(pad "B22" smd rect
			(at 6.45 5.895 180)
			(size 0.7 4.2)
			(layers "F.Cu" "F.Mask" "F.Paste")
			(net 60 "GND")
			(pinfunction "GND")
			(pintype "passive")
		)
		(pad "B23" smd rect
			(at 7.45 5.895 180)
			(size 0.7 4.2)
			(layers "F.Cu" "F.Mask" "F.Paste")
			(net 44 "/Data_2_OUT_P")
			(pinfunction "HSOp(2)")
			(pintype "passive")
		)
		(pad "B24" smd rect
			(at 8.45 5.895 180)
			(size 0.7 4.2)
			(layers "F.Cu" "F.Mask" "F.Paste")
			(net 45 "/Data_2_OUT_N")
			(pinfunction "HSOn(2)")
			(pintype "passive")
		)
		(pad "B25" smd rect
			(at 9.45 5.895 180)
			(size 0.7 4.2)
			(layers "F.Cu" "F.Mask" "F.Paste")
			(net 60 "GND")
			(pinfunction "GND")
			(pintype "passive")
		)
		(pad "B26" smd rect
			(at 10.45 5.895 180)
			(size 0.7 4.2)
			(layers "F.Cu" "F.Mask" "F.Paste")
			(net 60 "GND")
			(pinfunction "GND")
			(pintype "passive")
		)
		(pad "B27" smd rect
			(at 11.45 5.895 180)
			(size 0.7 4.2)
			(layers "F.Cu" "F.Mask" "F.Paste")
			(net 48 "/Data_3_OUT_P")
			(pinfunction "HSOp(3)")
			(pintype "passive")
		)
		(pad "B28" smd rect
			(at 12.45 5.895 180)
			(size 0.7 4.2)
			(layers "F.Cu" "F.Mask" "F.Paste")
			(net 49 "/Data_3_OUT_N")
			(pinfunction "HSOn(3)")
			(pintype "passive")
		)
		(pad "B29" smd rect
			(at 13.45 5.895 180)
			(size 0.7 4.2)
			(layers "F.Cu" "F.Mask" "F.Paste")
			(net 60 "GND")
			(pinfunction "GND")
			(pintype "passive")
		)
		(pad "B30" smd rect
			(at 14.45 5.895 180)
			(size 0.7 4.2)
			(layers "F.Cu" "F.Mask" "F.Paste")
			(net 2 "unconnected-(J1-RSVD-PadB30)")
			(pinfunction "RSVD")
			(pintype "passive+no_connect")
		)
		(pad "B31" smd rect
			(at 15.45 5.895 180)
			(size 0.7 4.2)
			(layers "F.Cu" "F.Mask" "F.Paste")
			(net 1 "unconnected-(J1-PRSNT#2-PadB31)")
			(pinfunction "PRSNT#2")
			(pintype "passive+no_connect")
		)
		(pad "B32" smd rect
			(at 16.45 5.895 180)
			(size 0.7 4.2)
			(layers "F.Cu" "F.Mask" "F.Paste")
			(net 60 "GND")
			(pinfunction "GND")
			(pintype "passive")
		)
	)
	(footprint "antmicro-footprints:Harwin_1x1_H3.5mm_Pad2.2mm_P70-1000045R"
		(layer "F.Cu")
		(at 179.200059 101.287277)
		(property "Reference" "J4"
			(at 0 -1.31 0)
			(layer "F.SilkS")
			(effects
				(font
					(size 0.7 0.7)
					(thickness 0.15)
				)
				(justify left bottom)
			)
		)
		(property "Value" "Harwin_1x1_H3.5mm_Pad2.2mm_P70-1000045R"
			(at 0 2.2 0)
			(layer "F.Fab")
			(effects
				(font
					(size 0.7 0.7)
					(thickness 0.15)
				)
				(justify left bottom)
			)
		)
		(property "Datasheet" "https://eu.mouser.com/datasheet/2/181/P70_10X-1018735.pdf"
			(at 0 0 0)
			(layer "F.Fab")
			(hide yes)
			(effects
				(font
					(size 1.27 1.27)
					(thickness 0.15)
				)
			)
		)
		(property "Description" "Contact Spring Surface Mount"
			(at 0 0 0)
			(layer "F.Fab")
			(hide yes)
			(effects
				(font
					(size 1.27 1.27)
					(thickness 0.15)
				)
			)
		)
		(property "Author" "Antmicro"
			(at 0 0 0)
			(layer "F.Fab")
			(hide yes)
			(effects
				(font
					(size 1 1)
					(thickness 0.15)
				)
			)
		)
		(property "License" "Apache-2.0"
			(at 0 0 0)
			(layer "F.Fab")
			(hide yes)
			(effects
				(font
					(size 1 1)
					(thickness 0.15)
				)
			)
		)
		(property "MPN" "P70-1000045R"
			(at 0 0 0)
			(layer "F.Fab")
			(hide yes)
			(effects
				(font
					(size 1 1)
					(thickness 0.15)
				)
			)
		)
		(property "Manufacturer" "Harwin"
			(at 0 0 0)
			(layer "F.Fab")
			(hide yes)
			(effects
				(font
					(size 1 1)
					(thickness 0.15)
				)
			)
		)
		(sheetname "/")
		(sheetfile "m2-pcie-adapter.kicad_sch")
		(attr smd)
		(fp_circle
			(center 0 0)
			(end 1.18 0)
			(stroke
				(width 0.15)
				(type solid)
			)
			(fill no)
			(layer "F.SilkS")
		)
		(fp_circle
			(center 0 0)
			(end 0 -1.25)
			(stroke
				(width 0.05)
				(type solid)
			)
			(fill no)
			(layer "F.CrtYd")
		)
		(pad "1" smd circle
			(at 0 0)
			(size 2.2 2.2)
			(layers "F.Cu" "F.Mask" "F.Paste")
			(net 30 "+12V")
			(pintype "passive")
		)
	)
	(footprint "antmicro-footprints:Harwin_1x1_H3.5mm_Pad2.2mm_P70-1000045R"
		(layer "F.Cu")
		(at 179.190059 96.267277)
		(property "Reference" "J5"
			(at 0 -1.31 0)
			(layer "F.SilkS")
			(effects
				(font
					(size 0.7 0.7)
					(thickness 0.15)
				)
				(justify left bottom)
			)
		)
		(property "Value" "Harwin_1x1_H3.5mm_Pad2.2mm_P70-1000045R"
			(at 0 2.2 0)
			(layer "F.Fab")
			(effects
				(font
					(size 0.7 0.7)
					(thickness 0.15)
				)
				(justify left bottom)
			)
		)
		(property "Datasheet" "https://eu.mouser.com/datasheet/2/181/P70_10X-1018735.pdf"
			(at 0 0 0)
			(layer "F.Fab")
			(hide yes)
			(effects
				(font
					(size 1.27 1.27)
					(thickness 0.15)
				)
			)
		)
		(property "Description" "Contact Spring Surface Mount"
			(at 0 0 0)
			(layer "F.Fab")
			(hide yes)
			(effects
				(font
					(size 1.27 1.27)
					(thickness 0.15)
				)
			)
		)
		(property "Author" "Antmicro"
			(at 0 0 0)
			(layer "F.Fab")
			(hide yes)
			(effects
				(font
					(size 1 1)
					(thickness 0.15)
				)
			)
		)
		(property "License" "Apache-2.0"
			(at 0 0 0)
			(layer "F.Fab")
			(hide yes)
			(effects
				(font
					(size 1 1)
					(thickness 0.15)
				)
			)
		)
		(property "MPN" "P70-1000045R"
			(at 0 0 0)
			(layer "F.Fab")
			(hide yes)
			(effects
				(font
					(size 1 1)
					(thickness 0.15)
				)
			)
		)
		(property "Manufacturer" "Harwin"
			(at 0 0 0)
			(layer "F.Fab")
			(hide yes)
			(effects
				(font
					(size 1 1)
					(thickness 0.15)
				)
			)
		)
		(sheetname "/")
		(sheetfile "m2-pcie-adapter.kicad_sch")
		(attr smd)
		(fp_circle
			(center 0 0)
			(end 1.18 0)
			(stroke
				(width 0.15)
				(type solid)
			)
			(fill no)
			(layer "F.SilkS")
		)
		(fp_circle
			(center 0 0)
			(end 0 -1.25)
			(stroke
				(width 0.05)
				(type solid)
			)
			(fill no)
			(layer "F.CrtYd")
		)
		(pad "1" smd circle
			(at 0 0)
			(size 2.2 2.2)
			(layers "F.Cu" "F.Mask" "F.Paste")
			(net 61 "+5V")
			(pintype "passive")
		)
	)
)
